# SCM (Grand Teton) — schematic netlist excerpt (pin names and nets, part order shuffled) for the footprints in the layout excerpt that follows; sources: Cadence DE-HDL packaged netlist, KiCad conversion of 12092022_DA0F0TMDCD0_F0T_Management_Board_D_brd_V3_OCP.brd

X6  TP_TDR_4P_FTS  TP_TDR_4P_DIP EMPTY  pkg TH  page 60
  S1  = TDR_DIFF_85_BOT_DP
  P1  = GND_P1
  P2  = GND_P1
  S2  = TDR_DIFF_85_BOT_DN

R699  Q_RES  4.7K 1% EMPTY  pkg 0402LF  page 27 : A = P3V3_AUX ; B = SPI_BMC_BOOT_CLK

(kicad_pcb
	(version 20260206)
	(generator "pcbnew")
	(generator_version "10.0")
	(general
		(thickness 1.6)
		(legacy_teardrops no)
	)
	(paper "A4")
	(title_block
		(title "12092022_DA0F0TMDCD0_F0T_Management_Board_D_brd_V3_OCP.brd")
		(comment 1 "Grand Teton / footprints 708-709 of 1440")
	)
	(layers
		(0 "F.Cu" signal "TOP")
		(4 "In1.Cu" signal "GND")
		(6 "In2.Cu" signal "IN1")
		(8 "In3.Cu" signal "GND1")
		(10 "In4.Cu" signal "IN2")
		(12 "In5.Cu" signal "VCC")
		(14 "In6.Cu" signal "VCC1")
		(16 "In7.Cu" signal "IN3")
		(18 "In8.Cu" signal "GND2")
		(20 "In9.Cu" signal "IN4")
		(22 "In10.Cu" signal "GND3")
		(2 "B.Cu" signal "BOTTOM")
		(9 "F.Adhes" user "F.Adhesive")
		(11 "B.Adhes" user "B.Adhesive")
		(13 "F.Paste" user "Package Geometry/Pastemask Top")
		(15 "B.Paste" user "Package Geometry/Pastemask Bottom")
		(5 "F.SilkS" user "Ref Des/Silkscreen Top")
		(7 "B.SilkS" user "Ref Des/Silkscreen Bottom")
		(1 "F.Mask" user "Board Geometry/Soldermask Top")
		(3 "B.Mask" user "Board Geometry/Soldermask Bottom")
		(17 "Dwgs.User" user "User.Drawings")
		(19 "Cmts.User" user "User.Comments")
		(21 "Eco1.User" user "User.Eco1")
		(23 "Eco2.User" user "User.Eco2")
		(25 "Edge.Cuts" user "Board Geometry/Outline")
		(27 "Margin" user)
		(31 "F.CrtYd" user "Package Geometry/Place Bound Top")
		(29 "B.CrtYd" user "Package Geometry/Place Bound Bottom")
		(35 "F.Fab" user "Ref Des/Assembly Top")
		(33 "B.Fab" user "Ref Des/Assembly Bottom")
	)
	(footprint ""
		(layer "F.Cu")
		(at 51.816 -69.342)
		(property "Reference" "R699"
			(at 0 0 0)
			(layer "F.SilkS")
			(hide yes)
			(effects
				(font
					(size 1.27 1.27)
				)
			)
		)
		(property "Value" ""
			(at 0 0 0)
			(layer "F.Fab")
			(effects
				(font
					(size 1.27 1.27)
				)
			)
		)
		(duplicate_pad_numbers_are_jumpers no)
		(fp_line
			(start -0.7874 -0.4064)
			(end 0.7874 -0.4064)
			(stroke
				(width 0.1524)
				(type default)
			)
			(layer "F.SilkS")
		)
		(fp_line
			(start -0.7874 0.4064)
			(end -0.7874 -0.4064)
			(stroke
				(width 0.1524)
				(type default)
			)
			(layer "F.SilkS")
		)
		(fp_line
			(start 0.7874 -0.4064)
			(end 0.7874 0.4064)
			(stroke
				(width 0.1524)
				(type default)
			)
			(layer "F.SilkS")
		)
		(fp_line
			(start 0.7874 0.4064)
			(end -0.7874 0.4064)
			(stroke
				(width 0.1524)
				(type default)
			)
			(layer "F.SilkS")
		)
		(fp_line
			(start -0.67945 -0.305054)
			(end -0.12065 -0.305054)
			(stroke
				(width 0.1)
				(type default)
			)
			(layer "F.Fab")
		)
		(fp_line
			(start -0.67945 0.3048)
			(end -0.67945 -0.305054)
			(stroke
				(width 0.1)
				(type default)
			)
			(layer "F.Fab")
		)
		(fp_line
			(start -0.12065 -0.305054)
			(end -0.12065 -0.2794)
			(stroke
				(width 0.1)
				(type default)
			)
			(layer "F.Fab")
		)
		(fp_line
			(start -0.12065 -0.2794)
			(end 0.12065 -0.2794)
			(stroke
				(width 0.1)
				(type default)
			)
			(layer "F.Fab")
		)
		(fp_line
			(start -0.12065 0.2794)
			(end -0.12065 0.3048)
			(stroke
				(width 0.1)
				(type default)
			)
			(layer "F.Fab")
		)
		(fp_line
			(start -0.12065 0.3048)
			(end -0.67945 0.3048)
			(stroke
				(width 0.1)
				(type default)
			)
			(layer "F.Fab")
		)
		(fp_line
			(start 0.120396 0.2794)
			(end -0.12065 0.2794)
			(stroke
				(width 0.1)
				(type default)
			)
			(layer "F.Fab")
		)
		(fp_line
			(start 0.120396 0.3048)
			(end 0.120396 0.2794)
			(stroke
				(width 0.1)
				(type default)
			)
			(layer "F.Fab")
		)
		(fp_line
			(start 0.12065 -0.3048)
			(end 0.67945 -0.3048)
			(stroke
				(width 0.1)
				(type default)
			)
			(layer "F.Fab")
		)
		(fp_line
			(start 0.12065 -0.2794)
			(end 0.12065 -0.3048)
			(stroke
				(width 0.1)
				(type default)
			)
			(layer "F.Fab")
		)
		(fp_line
			(start 0.67945 -0.3048)
			(end 0.67945 0.3048)
			(stroke
				(width 0.1)
				(type default)
			)
			(layer "F.Fab")
		)
		(fp_line
			(start 0.67945 0.3048)
			(end 0.120396 0.3048)
			(stroke
				(width 0.1)
				(type default)
			)
			(layer "F.Fab")
		)
		(pad "1" smd circle
			(at -0.40005 0)
			(size 0 0)
			(layers "F.Cu" "F.Mask" "F.Paste")
			(net "P3V3_AUX")
		)
		(pad "2" smd circle
			(at 0.40005 0)
			(size 0 0)
			(layers "F.Cu" "F.Mask" "F.Paste")
			(net "SPI_BMC_BOOT_CLK")
		)
	)
	(footprint ""
		(layer "F.Cu")
		(at 114.554 -3.048 -90)
		(property "Reference" "X6"
			(at -1.73863 -0.8382 0)
			(unlocked yes)
			(layer "F.SilkS")
			(effects
				(font
					(size 0.7874 0.5842)
					(thickness 0.1524)
				)
				(justify left)
			)
		)
		(property "Value" ""
			(at 0 0 270)
			(layer "F.Fab")
			(effects
				(font
					(size 1.27 1.27)
				)
			)
		)
		(property "Device Type" "TP_TDR_4P_FTS_TH-TP_TDR_4P_DIPA"
			(at 1.30175 1.27 0)
			(unlocked yes)
			(layer "F.Fab")
			(hide yes)
			(effects
				(font
					(size 0.635 0.4064)
					(thickness 0.1524)
				)
			)
		)
		(property "User Part Number" "N_A"
			(at 1.30175 1.27 0)
			(unlocked yes)
			(layer "Cmts.User")
			(hide yes)
			(effects
				(font
					(size 0.635 0.4064)
					(thickness 0.1524)
				)
			)
		)
		(duplicate_pad_numbers_are_jumpers no)
		(fp_line
			(start 0 3.81)
			(end 2.54 3.81)
			(stroke
				(width 0.1524)
				(type default)
			)
			(layer "F.SilkS")
		)
		(fp_line
			(start 2.54 3.81)
			(end 2.54 3.6703)
			(stroke
				(width 0.1524)
				(type default)
			)
			(layer "F.SilkS")
		)
		(fp_line
			(start 0 3.175)
			(end 0 3.81)
			(stroke
				(width 0.1524)
				(type default)
			)
			(layer "F.SilkS")
		)
		(fp_line
			(start 2.54 1.4097)
			(end 2.54 1.1303)
			(stroke
				(width 0.1524)
				(type default)
			)
			(layer "F.SilkS")
		)
		(fp_line
			(start 0 0.635)
			(end 0 1.905)
			(stroke
				(width 0.1524)
				(type default)
			)
			(layer "F.SilkS")
		)
		(fp_line
			(start 2.54 -1.1303)
			(end 2.54 -1.27)
			(stroke
				(width 0.1524)
				(type default)
			)
			(layer "F.SilkS")
		)
		(fp_line
			(start 0 -1.27)
			(end 0 -0.635)
			(stroke
				(width 0.1524)
				(type default)
			)
			(layer "F.SilkS")
		)
		(fp_line
			(start 2.54 -1.27)
			(end 0 -1.27)
			(stroke
				(width 0.1524)
				(type default)
			)
			(layer "F.SilkS")
		)
		(fp_poly
			(pts
				(xy -0.761746 0) (xy -2.285746 -0.762) (xy -2.285746 0.762)
			)
			(stroke
				(width 0)
				(type default)
			)
			(fill yes)
			(layer "F.SilkS")
		)
		(fp_line
			(start 0 3.81)
			(end 2.54 3.81)
			(stroke
				(width 0.1)
				(type default)
			)
			(layer "F.Fab")
		)
		(fp_line
			(start 2.54 3.81)
			(end 2.54 -1.27)
			(stroke
				(width 0.1)
				(type default)
			)
			(layer "F.Fab")
		)
		(fp_line
			(start 0 -1.27)
			(end 0 3.81)
			(stroke
				(width 0.1)
				(type default)
			)
			(layer "F.Fab")
		)
		(fp_line
			(start 2.54 -1.27)
			(end 0 -1.27)
			(stroke
				(width 0.1)
				(type default)
			)
			(layer "F.Fab")
		)
		(fp_poly
			(pts
				(xy -0.761746 0) (xy -2.285746 -0.762) (xy -2.285746 0.762)
			)
			(stroke
				(width 0)
				(type default)
			)
			(fill yes)
			(layer "F.Fab")
		)
		(pad "1" thru_hole circle
			(at 0 0 270)
			(size 1.0033 1.0033)
			(drill 0.249936)
			(layers "*.Cu" "*.Mask")
			(remove_unused_layers no)
			(net "TDR_DIFF_85_BOT_DP")
			(clearance 0.10795)
			(thermal_gap 0.10795)
			(padstack
				(mode front_inner_back)
				(layer "Inner"
					(shape circle)
					(size 0.8001 0.8001)
					(clearance 0.1524)
				)
				(layer "B.Cu"
					(shape circle)
					(size 1.0033 1.0033)
					(clearance 0.10795)
				)
			)
		)
		(pad "2" thru_hole circle
			(at 2.54 0 270)
			(size 1.9939 1.9939)
			(drill 0.249936)
			(layers "*.Cu" "*.Mask")
			(remove_unused_layers no)
			(net "GND_P1")
			(clearance 0.10795)
			(thermal_gap 0.10795)
			(padstack
				(mode front_inner_back)
				(layer "Inner"
					(shape circle)
					(size 0.8001 0.8001)
					(clearance 0.1524)
				)
				(layer "B.Cu"
					(shape circle)
					(size 1.9939 1.9939)
					(clearance 0.10795)
				)
			)
		)
		(pad "3" thru_hole circle
			(at 2.54 2.54 270)
			(size 1.9939 1.9939)
			(drill 0.249936)
			(layers "*.Cu" "*.Mask")
			(remove_unused_layers no)
			(net "GND_P1")
			(clearance 0.10795)
			(thermal_gap 0.10795)
			(padstack
				(mode front_inner_back)
				(layer "Inner"
					(shape circle)
					(size 0.8001 0.8001)
					(clearance 0.1524)
				)
				(layer "B.Cu"
					(shape circle)
					(size 1.9939 1.9939)
					(clearance 0.10795)
				)
			)
		)
		(pad "4" thru_hole circle
			(at 0 2.54 270)
			(size 1.0033 1.0033)
			(drill 0.249936)
			(layers "*.Cu" "*.Mask")
			(remove_unused_layers no)
			(net "TDR_DIFF_85_BOT_DN")
			(clearance 0.10795)
			(thermal_gap 0.10795)
			(padstack
				(mode front_inner_back)
				(layer "Inner"
					(shape circle)
					(size 0.8001 0.8001)
					(clearance 0.1524)
				)
				(layer "B.Cu"
					(shape circle)
					(size 1.0033 1.0033)
					(clearance 0.10795)
				)
			)
		)
	)
)
